FILE_TYPE=LIBRARY_PARTS;
primitive 'PI3CSW12ZUAEX';
  pin
    '1D+':
      PIN_NUMBER='(1)';
      BIDIRECTIONAL='TRUE';
      INPUT_LOAD='(-0.01,0.01)';
      OUTPUT_LOAD='(1.0,-1.0)';
    '2D+':
      PIN_NUMBER='(3)';
      BIDIRECTIONAL='TRUE';
      INPUT_LOAD='(-0.01,0.01)';
      OUTPUT_LOAD='(1.0,-1.0)';
    '2D-':
      PIN_NUMBER='(4)';
      BIDIRECTIONAL='TRUE';
      INPUT_LOAD='(-0.01,0.01)';
      OUTPUT_LOAD='(1.0,-1.0)';
    'D-':
      PIN_NUMBER='(7)';
      BIDIRECTIONAL='TRUE';
      INPUT_LOAD='(-0.01,0.01)';
      OUTPUT_LOAD='(1.0,-1.0)';
    'OE#':
      PIN_NUMBER='(6)';
      INPUT_LOAD='(-0.01,0.01)';
    'S':
      PIN_NUMBER='(9)';
      INPUT_LOAD='(-0.01,0.01)';
    'VDD':
      PIN_NUMBER='(10)';
      PINUSE='POWER';
      NO_LOAD_CHECK='Both';
      NO_IO_CHECK='Both';
      NO_ASSERT_CHECK='TRUE';
      NO_DIR_CHECK='TRUE';
      ALLOW_CONNECT='TRUE';
    '1D-':
      PIN_NUMBER='(2)';
      BIDIRECTIONAL='TRUE';
      INPUT_LOAD='(-0.01,0.01)';
      OUTPUT_LOAD='(1.0,-1.0)';
    'GND':
      PIN_NUMBER='(5)';
      PINUSE='POWER';
      NO_LOAD_CHECK='Both';
      NO_IO_CHECK='Both';
      NO_ASSERT_CHECK='TRUE';
      NO_DIR_CHECK='TRUE';
      ALLOW_CONNECT='TRUE';
    'D+':
      PIN_NUMBER='(8)';
      BIDIRECTIONAL='TRUE';
      INPUT_LOAD='(-0.01,0.01)';
      OUTPUT_LOAD='(1.0,-1.0)';
  end_pin;
  body
    PART_NAME='PI3CSW12ZUAEX';
    BODY_NAME='PI3CSW12ZUAEX';
    PHYS_DES_PREFIX='U';
    CLASS='IC';
  end_body;
end_primitive;

END.
